(kicad_pcb
	(version 20260206)
	(generator "pcbnew")
	(generator_version "10.0")
	(general
		(thickness 1.6)
		(legacy_teardrops no)
	)
	(paper "A4")
	(title_block
		(title "01162023_DA0F0TEBIF0_F0T_Expander_BD_F_brd_V02_OCP.brd")
		(comment 1 "Grand Teton / footprints 6896-6901 of 9728")
	)
	(layers
		(0 "F.Cu" signal "TOP")
		(4 "In1.Cu" signal "GND")
		(6 "In2.Cu" signal "VCC")
		(8 "In3.Cu" signal "VCC1")
		(10 "In4.Cu" signal "GND1")
		(12 "In5.Cu" signal "IN1")
		(14 "In6.Cu" signal "GND2")
		(16 "In7.Cu" signal "IN2")
		(18 "In8.Cu" signal "GND3")
		(20 "In9.Cu" signal "IN3")
		(22 "In10.Cu" signal "GND4")
		(24 "In11.Cu" signal "IN4")
		(26 "In12.Cu" signal "GND5")
		(28 "In13.Cu" signal "IN5")
		(30 "In14.Cu" signal "GND6")
		(32 "In15.Cu" signal "IN6")
		(34 "In16.Cu" signal "GND7")
		(2 "B.Cu" signal "BOTTOM")
		(9 "F.Adhes" user "F.Adhesive")
		(11 "B.Adhes" user "B.Adhesive")
		(13 "F.Paste" user "Package Geometry/Pastemask Top")
		(15 "B.Paste" user "Package Geometry/Pastemask Bottom")
		(5 "F.SilkS" user "Ref Des/Silkscreen Top")
		(7 "B.SilkS" user "Ref Des/Silkscreen Bottom")
		(1 "F.Mask" user "Board Geometry/Soldermask Top")
		(3 "B.Mask" user "Board Geometry/Soldermask Bottom")
		(17 "Dwgs.User" user "User.Drawings")
		(19 "Cmts.User" user "User.Comments")
		(21 "Eco1.User" user "User.Eco1")
		(23 "Eco2.User" user "User.Eco2")
		(25 "Edge.Cuts" user "Board Geometry/Outline")
		(27 "Margin" user)
		(31 "F.CrtYd" user "Package Geometry/Place Bound Top")
		(29 "B.CrtYd" user "Package Geometry/Place Bound Bottom")
		(35 "F.Fab" user "Ref Des/Assembly Top")
		(33 "B.Fab" user "Ref Des/Assembly Bottom")
	)
	(footprint ""
		(layer "F.Cu")
		(at 230.294434 -368.957606 180)
		(property "Reference" "PU3"
			(at -5.235448 -2.776982 0)
			(unlocked yes)
			(layer "F.SilkS")
			(effects
				(font
					(size 0.7874 0.5842)
					(thickness 0.1524)
				)
			)
		)
		(property "Value" ""
			(at 0 0 180)
			(layer "F.Fab")
			(effects
				(font
					(size 1.27 1.27)
				)
			)
		)
		(duplicate_pad_numbers_are_jumpers no)
		(fp_line
			(start 2.567686 2.567686)
			(end 2.567686 -2.567686)
			(stroke
				(width 0.1524)
				(type default)
			)
			(layer "F.SilkS")
		)
		(fp_line
			(start 2.567686 -2.567686)
			(end -2.567686 -2.567686)
			(stroke
				(width 0.1524)
				(type default)
			)
			(layer "F.SilkS")
		)
		(fp_line
			(start -2.567686 2.567686)
			(end 2.567686 2.567686)
			(stroke
				(width 0.1524)
				(type default)
			)
			(layer "F.SilkS")
		)
		(fp_line
			(start -2.567686 -2.567686)
			(end -2.567686 2.567686)
			(stroke
				(width 0.1524)
				(type default)
			)
			(layer "F.SilkS")
		)
		(fp_poly
			(pts
				(xy -2.965704 -3.687064) (xy -3.684016 -2.968752) (xy -2.606548 -2.609342)
			)
			(stroke
				(width 0)
				(type default)
			)
			(fill yes)
			(layer "F.SilkS")
		)
		(fp_line
			(start 2.549906 2.549906)
			(end 2.549906 -2.549906)
			(stroke
				(width 0.1)
				(type default)
			)
			(layer "F.Fab")
		)
		(fp_line
			(start 2.549906 -2.549906)
			(end -2.549906 -2.549906)
			(stroke
				(width 0.1)
				(type default)
			)
			(layer "F.Fab")
		)
		(fp_line
			(start -2.549906 2.549906)
			(end 2.549906 2.549906)
			(stroke
				(width 0.1)
				(type default)
			)
			(layer "F.Fab")
		)
		(fp_line
			(start -2.549906 -2.549906)
			(end -2.549906 2.549906)
			(stroke
				(width 0.1)
				(type default)
			)
			(layer "F.Fab")
		)
		(fp_poly
			(pts
				(xy -3.806698 -2.25806) (xy -3.806698 -1.24206) (xy -2.790698 -1.75006)
			)
			(stroke
				(width 0)
				(type default)
			)
			(fill yes)
			(layer "F.Fab")
		)
		(pad "1" smd rect
			(at -2.250186 -1.75006 270)
			(size 0.254 0.3556)
			(layers "F.Cu" "F.Mask" "F.Paste")
			(net "P12V_AUX")
		)
		(pad "2" smd rect
			(at -2.237486 -1.249934 270)
			(size 0.254 0.381)
			(layers "F.Cu" "F.Mask" "F.Paste")
			(net "P12V_AUX")
		)
		(pad "3" smd rect
			(at -2.237486 -0.750062 270)
			(size 0.254 0.381)
			(layers "F.Cu" "F.Mask" "F.Paste")
			(net "HSC_D_OC_2")
		)
		(pad "4" smd rect
			(at -2.237486 -0.249936 270)
			(size 0.254 0.381)
			(layers "F.Cu" "F.Mask" "F.Paste")
			(net "HSC_ON")
		)
		(pad "5" smd rect
			(at -2.237486 0.249936 270)
			(size 0.254 0.381)
			(layers "F.Cu" "F.Mask" "F.Paste")
			(net "HSC_FAULT_N_2")
		)
		(pad "6" smd rect
			(at -2.237486 0.750062 270)
			(size 0.254 0.381)
			(layers "F.Cu" "F.Mask" "F.Paste")
			(net "HSC_FLT_TYPE_2")
		)
		(pad "7" smd rect
			(at -2.237486 1.249934 270)
			(size 0.254 0.381)
			(layers "F.Cu" "F.Mask" "F.Paste")
			(net "Net_9083")
		)
		(pad "8" smd rect
			(at -2.250186 1.75006 270)
			(size 0.254 0.3556)
			(layers "F.Cu" "F.Mask" "F.Paste")
			(net "HSC_MODE_2")
		)
		(pad "9" smd rect
			(at -1.75006 2.250186 180)
			(size 0.254 0.3556)
			(layers "F.Cu" "F.Mask" "F.Paste")
			(net "P12V_STBY")
		)
		(pad "10" smd rect
			(at -1.249934 2.237486 180)
			(size 0.254 0.381)
			(layers "F.Cu" "F.Mask" "F.Paste")
			(net "P12V_STBY")
		)
		(pad "11" smd rect
			(at -0.750062 2.237486 180)
			(size 0.254 0.381)
			(layers "F.Cu" "F.Mask" "F.Paste")
			(net "P12V_STBY")
		)
		(pad "12" smd rect
			(at -0.249936 2.237486 180)
			(size 0.254 0.381)
			(layers "F.Cu" "F.Mask" "F.Paste")
			(net "P12V_STBY")
		)
		(pad "13" smd rect
			(at 0.249936 2.237486 180)
			(size 0.254 0.381)
			(layers "F.Cu" "F.Mask" "F.Paste")
			(net "P12V_STBY")
		)
		(pad "14" smd rect
			(at 0.750062 2.237486 180)
			(size 0.254 0.381)
			(layers "F.Cu" "F.Mask" "F.Paste")
			(net "P12V_STBY")
		)
		(pad "15" smd rect
			(at 1.249934 2.237486 180)
			(size 0.254 0.381)
			(layers "F.Cu" "F.Mask" "F.Paste")
			(net "P12V_STBY")
		)
		(pad "16" smd rect
			(at 1.75006 2.250186 180)
			(size 0.254 0.3556)
			(layers "F.Cu" "F.Mask" "F.Paste")
			(net "P12V_STBY")
		)
		(pad "17" smd rect
			(at 2.250186 1.75006 270)
			(size 0.254 0.3556)
			(layers "F.Cu" "F.Mask" "F.Paste")
			(net "HSC_SCREF_2")
		)
		(pad "18" smd rect
			(at 2.237486 1.249934 270)
			(size 0.254 0.381)
			(layers "F.Cu" "F.Mask" "F.Paste")
			(net "HSC_VTEMP")
		)
		(pad "19" smd rect
			(at 2.237486 0.750062 270)
			(size 0.254 0.381)
			(layers "F.Cu" "F.Mask" "F.Paste")
			(net "HSC_SS")
		)
		(pad "20" smd rect
			(at 2.237486 0.249936 270)
			(size 0.254 0.381)
			(layers "F.Cu" "F.Mask" "F.Paste")
			(net "AGND_HSC")
		)
		(pad "21" smd rect
			(at 2.237486 -0.249936 270)
			(size 0.254 0.381)
			(layers "F.Cu" "F.Mask" "F.Paste")
			(net "HSC_VDD_2")
		)
		(pad "22" smd rect
			(at 2.237486 -0.750062 270)
			(size 0.254 0.381)
			(layers "F.Cu" "F.Mask" "F.Paste")
			(net "HSC_IMON")
		)
		(pad "23" smd rect
			(at 2.237486 -1.249934 270)
			(size 0.254 0.381)
			(layers "F.Cu" "F.Mask" "F.Paste")
			(net "HSC_CS_2")
		)
		(pad "24" smd rect
			(at 2.250186 -1.75006 270)
			(size 0.254 0.3556)
			(layers "F.Cu" "F.Mask" "F.Paste")
			(net "HSC_OCREF")
		)
		(pad "25" smd rect
			(at 1.75006 -2.250186 180)
			(size 0.254 0.3556)
			(layers "F.Cu" "F.Mask" "F.Paste")
			(net "P12V_AUX")
		)
		(pad "26" smd rect
			(at 1.249934 -2.237486 180)
			(size 0.254 0.381)
			(layers "F.Cu" "F.Mask" "F.Paste")
			(net "P12V_AUX")
		)
		(pad "27" smd rect
			(at 0.750062 -2.237486 180)
			(size 0.254 0.381)
			(layers "F.Cu" "F.Mask" "F.Paste")
			(net "P12V_AUX")
		)
		(pad "28" smd rect
			(at 0.249936 -2.237486 180)
			(size 0.254 0.381)
			(layers "F.Cu" "F.Mask" "F.Paste")
			(net "P12V_AUX")
		)
		(pad "29" smd rect
			(at -0.249936 -2.237486 180)
			(size 0.254 0.381)
			(layers "F.Cu" "F.Mask" "F.Paste")
			(net "P12V_AUX")
		)
		(pad "30" smd rect
			(at -0.750062 -2.237486 180)
			(size 0.254 0.381)
			(layers "F.Cu" "F.Mask" "F.Paste")
			(net "P12V_AUX")
		)
		(pad "31" smd rect
			(at -1.249934 -2.237486 180)
			(size 0.254 0.381)
			(layers "F.Cu" "F.Mask" "F.Paste")
			(net "P12V_AUX")
		)
		(pad "32" smd rect
			(at -1.75006 -2.250186 180)
			(size 0.254 0.3556)
			(layers "F.Cu" "F.Mask" "F.Paste")
			(net "P12V_AUX")
		)
		(pad "33" smd rect
			(at 0 0 180)
			(size 3.4036 3.4036)
			(layers "F.Cu" "F.Mask" "F.Paste")
			(net "P12V_STBY")
		)
	)
	(footprint ""
		(layer "F.Cu")
		(at 358.037892 -207.183482 180)
		(property "Reference" "R6422"
			(at 0 0 180)
			(layer "F.SilkS")
			(hide yes)
			(effects
				(font
					(size 1.27 1.27)
				)
			)
		)
		(property "Value" ""
			(at 0 0 180)
			(layer "F.Fab")
			(effects
				(font
					(size 1.27 1.27)
				)
			)
		)
		(duplicate_pad_numbers_are_jumpers no)
		(fp_line
			(start 0.7874 0.4064)
			(end -0.7874 0.4064)
			(stroke
				(width 0.1524)
				(type default)
			)
			(layer "F.SilkS")
		)
		(fp_line
			(start 0.7874 -0.4064)
			(end 0.7874 0.4064)
			(stroke
				(width 0.1524)
				(type default)
			)
			(layer "F.SilkS")
		)
		(fp_line
			(start -0.7874 0.4064)
			(end -0.7874 -0.4064)
			(stroke
				(width 0.1524)
				(type default)
			)
			(layer "F.SilkS")
		)
		(fp_line
			(start -0.7874 -0.4064)
			(end 0.7874 -0.4064)
			(stroke
				(width 0.1524)
				(type default)
			)
			(layer "F.SilkS")
		)
		(fp_line
			(start 0.67945 0.3048)
			(end 0.120396 0.3048)
			(stroke
				(width 0.1)
				(type default)
			)
			(layer "F.Fab")
		)
		(fp_line
			(start 0.67945 -0.3048)
			(end 0.67945 0.3048)
			(stroke
				(width 0.1)
				(type default)
			)
			(layer "F.Fab")
		)
		(fp_line
			(start 0.12065 -0.2794)
			(end 0.12065 -0.3048)
			(stroke
				(width 0.1)
				(type default)
			)
			(layer "F.Fab")
		)
		(fp_line
			(start 0.12065 -0.3048)
			(end 0.67945 -0.3048)
			(stroke
				(width 0.1)
				(type default)
			)
			(layer "F.Fab")
		)
		(fp_line
			(start 0.120396 0.3048)
			(end 0.120396 0.2794)
			(stroke
				(width 0.1)
				(type default)
			)
			(layer "F.Fab")
		)
		(fp_line
			(start 0.120396 0.2794)
			(end -0.12065 0.2794)
			(stroke
				(width 0.1)
				(type default)
			)
			(layer "F.Fab")
		)
		(fp_line
			(start -0.12065 0.3048)
			(end -0.67945 0.3048)
			(stroke
				(width 0.1)
				(type default)
			)
			(layer "F.Fab")
		)
		(fp_line
			(start -0.12065 0.2794)
			(end -0.12065 0.3048)
			(stroke
				(width 0.1)
				(type default)
			)
			(layer "F.Fab")
		)
		(fp_line
			(start -0.12065 -0.2794)
			(end 0.12065 -0.2794)
			(stroke
				(width 0.1)
				(type default)
			)
			(layer "F.Fab")
		)
		(fp_line
			(start -0.12065 -0.305054)
			(end -0.12065 -0.2794)
			(stroke
				(width 0.1)
				(type default)
			)
			(layer "F.Fab")
		)
		(fp_line
			(start -0.67945 0.3048)
			(end -0.67945 -0.305054)
			(stroke
				(width 0.1)
				(type default)
			)
			(layer "F.Fab")
		)
		(fp_line
			(start -0.67945 -0.305054)
			(end -0.12065 -0.305054)
			(stroke
				(width 0.1)
				(type default)
			)
			(layer "F.Fab")
		)
		(pad "1" smd circle
			(at -0.40005 0 180)
			(size 0 0)
			(layers "F.Cu" "F.Mask" "F.Paste")
			(net "FPGA_PEX3_MODE_SEL2_R")
		)
		(pad "2" smd circle
			(at 0.40005 0 180)
			(size 0 0)
			(layers "F.Cu" "F.Mask" "F.Paste")
			(net "FPGA_PEX3_MODE_SEL2")
		)
	)
	(footprint ""
		(layer "F.Cu")
		(at 214.757 -198.12)
		(property "Reference" "U121"
			(at -1.397 -2.13233 0)
			(unlocked yes)
			(layer "F.SilkS")
			(effects
				(font
					(size 0.7874 0.5842)
					(thickness 0.1524)
				)
				(justify left)
			)
		)
		(property "Value" ""
			(at 0 0 0)
			(layer "F.Fab")
			(effects
				(font
					(size 1.27 1.27)
				)
			)
		)
		(duplicate_pad_numbers_are_jumpers no)
		(fp_line
			(start -1.3208 -1.525016)
			(end -0.508 -1.525016)
			(stroke
				(width 0.1524)
				(type default)
			)
			(layer "F.SilkS")
		)
		(fp_line
			(start -1.3208 1.525016)
			(end -1.3208 -1.525016)
			(stroke
				(width 0.1524)
				(type default)
			)
			(layer "F.SilkS")
		)
		(fp_line
			(start -0.508 -1.525016)
			(end 0 -0.999998)
			(stroke
				(width 0.1524)
				(type default)
			)
			(layer "F.SilkS")
		)
		(fp_line
			(start 0 -0.999998)
			(end 0.508 -1.525016)
			(stroke
				(width 0.1524)
				(type default)
			)
			(layer "F.SilkS")
		)
		(fp_line
			(start 0.508 -1.525016)
			(end 1.3208 -1.525016)
			(stroke
				(width 0.1524)
				(type default)
			)
			(layer "F.SilkS")
		)
		(fp_line
			(start 1.3208 -1.525016)
			(end 1.3208 1.525016)
			(stroke
				(width 0.1524)
				(type default)
			)
			(layer "F.SilkS")
		)
		(fp_line
			(start 1.3208 1.525016)
			(end -1.3208 1.525016)
			(stroke
				(width 0.1524)
				(type default)
			)
			(layer "F.SilkS")
		)
		(fp_poly
			(pts
				(xy -2.897886 -1.428496) (xy -3.706114 -1.697736) (xy -3.167126 -2.236724)
			)
			(stroke
				(width 0)
				(type default)
			)
			(fill yes)
			(layer "F.SilkS")
		)
		(fp_line
			(start -3.037078 -1.20777)
			(end -1.524 -1.20777)
			(stroke
				(width 0.1)
				(type default)
			)
			(layer "F.Fab")
		)
		(fp_line
			(start -3.037078 1.203706)
			(end -3.037078 -1.20777)
			(stroke
				(width 0.1)
				(type default)
			)
			(layer "F.Fab")
		)
		(fp_line
			(start -1.5494 1.203706)
			(end -3.037078 1.203706)
			(stroke
				(width 0.1)
				(type default)
			)
			(layer "F.Fab")
		)
		(fp_line
			(start -1.5494 1.5494)
			(end -1.5494 1.203706)
			(stroke
				(width 0.1)
				(type default)
			)
			(layer "F.Fab")
		)
		(fp_line
			(start -1.524 -1.524)
			(end 1.524 -1.524)
			(stroke
				(width 0.1)
				(type default)
			)
			(layer "F.Fab")
		)
		(fp_line
			(start -1.524 -1.20777)
			(end -1.524 -1.524)
			(stroke
				(width 0.1)
				(type default)
			)
			(layer "F.Fab")
		)
		(fp_line
			(start 1.524 -1.524)
			(end 1.524 -1.20777)
			(stroke
				(width 0.1)
				(type default)
			)
			(layer "F.Fab")
		)
		(fp_line
			(start 1.524 -1.20777)
			(end 3.0353 -1.20777)
			(stroke
				(width 0.1)
				(type default)
			)
			(layer "F.Fab")
		)
		(fp_line
			(start 1.524 1.208786)
			(end 1.524 1.5494)
			(stroke
				(width 0.1)
				(type default)
			)
			(layer "F.Fab")
		)
		(fp_line
			(start 1.524 1.5494)
			(end -1.5494 1.5494)
			(stroke
				(width 0.1)
				(type default)
			)
			(layer "F.Fab")
		)
		(fp_line
			(start 3.0353 -1.20777)
			(end 3.0353 1.208786)
			(stroke
				(width 0.1)
				(type default)
			)
			(layer "F.Fab")
		)
		(fp_line
			(start 3.0353 1.208786)
			(end 1.524 1.208786)
			(stroke
				(width 0.1)
				(type default)
			)
			(layer "F.Fab")
		)
		(fp_poly
			(pts
				(xy -3.175 -1.016) (xy -3.937 -0.635) (xy -3.937 -1.397)
			)
			(stroke
				(width 0)
				(type default)
			)
			(fill yes)
			(layer "F.Fab")
		)
		(pad "1" smd rect
			(at -2.234946 -0.975106 270)
			(size 0.3556 1.4986)
			(layers "F.Cu" "F.Mask" "F.Paste")
			(net "P1V2_AUX")
		)
		(pad "2" smd rect
			(at -2.234946 -0.32512 270)
			(size 0.3556 1.4986)
			(layers "F.Cu" "F.Mask" "F.Paste")
			(net "SMB_NIC6_R_SDA")
		)
		(pad "3" smd rect
			(at -2.234946 0.32512 270)
			(size 0.3556 1.4986)
			(layers "F.Cu" "F.Mask" "F.Paste")
			(net "SMB_NIC6_R_SCL")
		)
		(pad "4" smd rect
			(at -2.234946 0.975106 270)
			(size 0.3556 1.4986)
			(layers "F.Cu" "F.Mask" "F.Paste")
			(net "GND")
		)
		(pad "5" smd rect
			(at 2.234946 0.975106 270)
			(size 0.3556 1.4986)
			(layers "F.Cu" "F.Mask" "F.Paste")
			(net "SMB_NIC6_LS_EN")
		)
		(pad "6" smd rect
			(at 2.234946 0.32512 270)
			(size 0.3556 1.4986)
			(layers "F.Cu" "F.Mask" "F.Paste")
			(net "SMB_NIC6_LS_R_SCL")
		)
		(pad "7" smd rect
			(at 2.234946 -0.32512 270)
			(size 0.3556 1.4986)
			(layers "F.Cu" "F.Mask" "F.Paste")
			(net "SMB_NIC6_LS_R_SDA")
		)
		(pad "8" smd rect
			(at 2.234946 -0.975106 270)
			(size 0.3556 1.4986)
			(layers "F.Cu" "F.Mask" "F.Paste")
			(net "P3V3_NIC6")
		)
	)
	(footprint ""
		(layer "F.Cu")
		(at 239.754918 -312.316114 180)
		(property "Reference" "PC244"
			(at 0 0 180)
			(layer "F.SilkS")
			(hide yes)
			(effects
				(font
					(size 1.27 1.27)
				)
			)
		)
		(property "Value" ""
			(at 0 0 180)
			(layer "F.Fab")
			(effects
				(font
					(size 1.27 1.27)
				)
			)
		)
		(duplicate_pad_numbers_are_jumpers no)
		(fp_line
			(start 1.524 0.762)
			(end -1.524 0.762)
			(stroke
				(width 0.1524)
				(type default)
			)
			(layer "F.SilkS")
		)
		(fp_line
			(start 1.524 -0.762)
			(end 1.524 0.762)
			(stroke
				(width 0.1524)
				(type default)
			)
			(layer "F.SilkS")
		)
		(fp_line
			(start -1.524 0.762)
			(end -1.524 -0.762)
			(stroke
				(width 0.1524)
				(type default)
			)
			(layer "F.SilkS")
		)
		(fp_line
			(start -1.524 -0.762)
			(end 1.524 -0.762)
			(stroke
				(width 0.1524)
				(type default)
			)
			(layer "F.SilkS")
		)
		(fp_line
			(start 1.1049 0.724916)
			(end 1.1049 -0.724916)
			(stroke
				(width 0.1)
				(type default)
			)
			(layer "F.Fab")
		)
		(fp_line
			(start 1.1049 -0.724916)
			(end -1.1049 -0.724916)
			(stroke
				(width 0.1)
				(type default)
			)
			(layer "F.Fab")
		)
		(fp_line
			(start -1.1049 0.724916)
			(end 1.1049 0.724916)
			(stroke
				(width 0.1)
				(type default)
			)
			(layer "F.Fab")
		)
		(fp_line
			(start -1.1049 -0.724916)
			(end -1.1049 0.724916)
			(stroke
				(width 0.1)
				(type default)
			)
			(layer "F.Fab")
		)
		(pad "1" smd rect
			(at -0.889 0)
			(size 1.016 1.27)
			(layers "F.Cu" "F.Mask" "F.Paste")
			(net "SW_P12V_P1V25_PEX2_FLT")
		)
		(pad "2" smd rect
			(at 0.889 0)
			(size 1.016 1.27)
			(layers "F.Cu" "F.Mask" "F.Paste")
			(net "GND")
		)
	)
	(footprint ""
		(layer "F.Cu")
		(at 31.007304 -260.639814 -90)
		(property "Reference" "C3034"
			(at 0 0 270)
			(layer "F.SilkS")
			(hide yes)
			(effects
				(font
					(size 1.27 1.27)
				)
			)
		)
		(property "Value" ""
			(at 0 0 270)
			(layer "F.Fab")
			(effects
				(font
					(size 1.27 1.27)
				)
			)
		)
		(duplicate_pad_numbers_are_jumpers no)
		(fp_line
			(start -0.299974 0.150114)
			(end -0.299974 -0.150114)
			(stroke
				(width 0.1)
				(type default)
			)
			(layer "F.Fab")
		)
		(fp_line
			(start 0.299974 0.150114)
			(end -0.299974 0.150114)
			(stroke
				(width 0.1)
				(type default)
			)
			(layer "F.Fab")
		)
		(fp_line
			(start -0.299974 -0.150114)
			(end 0.299974 -0.150114)
			(stroke
				(width 0.1)
				(type default)
			)
			(layer "F.Fab")
		)
		(fp_line
			(start 0.299974 -0.150114)
			(end 0.299974 0.150114)
			(stroke
				(width 0.1)
				(type default)
			)
			(layer "F.Fab")
		)
		(pad "1" smd rect
			(at -0.2667 0 270)
			(size 0.3048 0.381)
			(layers "F.Cu" "F.Mask" "F.Paste")
			(net "P1V8_PLL0_PEX0")
		)
		(pad "2" smd rect
			(at 0.2667 0 270)
			(size 0.3048 0.381)
			(layers "F.Cu" "F.Mask" "F.Paste")
			(net "GND")
		)
	)
	(footprint ""
		(layer "F.Cu")
		(at 17.333214 -265.719052)
		(property "Reference" "C4224"
			(at 0 0 0)
			(layer "F.SilkS")
			(hide yes)
			(effects
				(font
					(size 1.27 1.27)
				)
			)
		)
		(property "Value" ""
			(at 0 0 0)
			(layer "F.Fab")
			(effects
				(font
					(size 1.27 1.27)
				)
			)
		)
		(duplicate_pad_numbers_are_jumpers no)
		(fp_line
			(start -0.299974 -0.150114)
			(end 0.299974 -0.150114)
			(stroke
				(width 0.1)
				(type default)
			)
			(layer "F.Fab")
		)
		(fp_line
			(start -0.299974 0.150114)
			(end -0.299974 -0.150114)
			(stroke
				(width 0.1)
				(type default)
			)
			(layer "F.Fab")
		)
		(fp_line
			(start 0.299974 -0.150114)
			(end 0.299974 0.150114)
			(stroke
				(width 0.1)
				(type default)
			)
			(layer "F.Fab")
		)
		(fp_line
			(start 0.299974 0.150114)
			(end -0.299974 0.150114)
			(stroke
				(width 0.1)
				(type default)
			)
			(layer "F.Fab")
		)
		(pad "1" smd rect
			(at -0.2667 0)
			(size 0.3048 0.381)
			(layers "F.Cu" "F.Mask" "F.Paste")
			(net "P1V25_SERDES_VDDPLL_PEX0")
		)
		(pad "2" smd rect
			(at 0.2667 0)
			(size 0.3048 0.381)
			(layers "F.Cu" "F.Mask" "F.Paste")
			(net "GND")
		)
	)
)
